(kicad_pcb
	(version 20260206)
	(generator "pcbnew")
	(generator_version "10.0")
	(general
		(thickness 1.6)
		(legacy_teardrops no)
	)
	(paper "A4")
	(title_block
		(title "04192023_DAF0TMB3IC0_F0TG_MB_C_brd_V02_OCP.brd")
		(comment 1 "Grand Teton / footprints 3445-3451 of 8354")
	)
	(layers
		(0 "F.Cu" signal "TOP")
		(4 "In1.Cu" signal "GND")
		(6 "In2.Cu" signal "IN1")
		(8 "In3.Cu" signal "GND1")
		(10 "In4.Cu" signal "IN2")
		(12 "In5.Cu" signal "GND2")
		(14 "In6.Cu" signal "IN3")
		(16 "In7.Cu" signal "GND3")
		(18 "In8.Cu" signal "VCC")
		(20 "In9.Cu" signal "VCC1")
		(22 "In10.Cu" signal "GND4")
		(24 "In11.Cu" signal "IN4")
		(26 "In12.Cu" signal "GND5")
		(28 "In13.Cu" signal "IN5")
		(30 "In14.Cu" signal "GND6")
		(32 "In15.Cu" signal "IN6")
		(34 "In16.Cu" signal "GND7")
		(2 "B.Cu" signal "BOTTOM")
		(9 "F.Adhes" user "F.Adhesive")
		(11 "B.Adhes" user "B.Adhesive")
		(13 "F.Paste" user "Package Geometry/Pastemask Top")
		(15 "B.Paste" user "Package Geometry/Pastemask Bottom")
		(5 "F.SilkS" user "Ref Des/Silkscreen Top")
		(7 "B.SilkS" user "Ref Des/Silkscreen Bottom")
		(1 "F.Mask" user "Board Geometry/Soldermask Top")
		(3 "B.Mask" user "Board Geometry/Soldermask Bottom")
		(17 "Dwgs.User" user "User.Drawings")
		(19 "Cmts.User" user "User.Comments")
		(21 "Eco1.User" user "User.Eco1")
		(23 "Eco2.User" user "User.Eco2")
		(25 "Edge.Cuts" user "Board Geometry/Outline")
		(27 "Margin" user)
		(31 "F.CrtYd" user "Package Geometry/Place Bound Top")
		(29 "B.CrtYd" user "Package Geometry/Place Bound Bottom")
		(35 "F.Fab" user "Ref Des/Assembly Top")
		(33 "B.Fab" user "Ref Des/Assembly Bottom")
	)
	(footprint ""
		(layer "F.Cu")
		(at 20.148042 -389.007858 -90)
		(property "Reference" "PC6612_1"
			(at 0 0 270)
			(layer "F.SilkS")
			(hide yes)
			(effects
				(font
					(size 1.27 1.27)
				)
			)
		)
		(property "Value" ""
			(at 0 0 270)
			(layer "F.Fab")
			(effects
				(font
					(size 1.27 1.27)
				)
			)
		)
		(duplicate_pad_numbers_are_jumpers no)
		(fp_line
			(start -0.7874 0.4064)
			(end -0.7874 -0.4064)
			(stroke
				(width 0.1524)
				(type default)
			)
			(layer "F.SilkS")
		)
		(fp_line
			(start 0.7874 0.4064)
			(end -0.7874 0.4064)
			(stroke
				(width 0.1524)
				(type default)
			)
			(layer "F.SilkS")
		)
		(fp_line
			(start -0.7874 -0.4064)
			(end 0.7874 -0.4064)
			(stroke
				(width 0.1524)
				(type default)
			)
			(layer "F.SilkS")
		)
		(fp_line
			(start 0.7874 -0.4064)
			(end 0.7874 0.4064)
			(stroke
				(width 0.1524)
				(type default)
			)
			(layer "F.SilkS")
		)
		(fp_line
			(start -0.67945 0.3048)
			(end -0.67945 -0.305054)
			(stroke
				(width 0.1)
				(type default)
			)
			(layer "F.Fab")
		)
		(fp_line
			(start -0.12065 0.3048)
			(end -0.67945 0.3048)
			(stroke
				(width 0.1)
				(type default)
			)
			(layer "F.Fab")
		)
		(fp_line
			(start 0.120396 0.3048)
			(end 0.120396 0.2794)
			(stroke
				(width 0.1)
				(type default)
			)
			(layer "F.Fab")
		)
		(fp_line
			(start 0.67945 0.3048)
			(end 0.120396 0.3048)
			(stroke
				(width 0.1)
				(type default)
			)
			(layer "F.Fab")
		)
		(fp_line
			(start -0.12065 0.2794)
			(end -0.12065 0.3048)
			(stroke
				(width 0.1)
				(type default)
			)
			(layer "F.Fab")
		)
		(fp_line
			(start 0.120396 0.2794)
			(end -0.12065 0.2794)
			(stroke
				(width 0.1)
				(type default)
			)
			(layer "F.Fab")
		)
		(fp_line
			(start -0.12065 -0.2794)
			(end 0.12065 -0.2794)
			(stroke
				(width 0.1)
				(type default)
			)
			(layer "F.Fab")
		)
		(fp_line
			(start 0.12065 -0.2794)
			(end 0.12065 -0.3048)
			(stroke
				(width 0.1)
				(type default)
			)
			(layer "F.Fab")
		)
		(fp_line
			(start 0.12065 -0.3048)
			(end 0.67945 -0.3048)
			(stroke
				(width 0.1)
				(type default)
			)
			(layer "F.Fab")
		)
		(fp_line
			(start 0.67945 -0.3048)
			(end 0.67945 0.3048)
			(stroke
				(width 0.1)
				(type default)
			)
			(layer "F.Fab")
		)
		(fp_line
			(start -0.67945 -0.305054)
			(end -0.12065 -0.305054)
			(stroke
				(width 0.1)
				(type default)
			)
			(layer "F.Fab")
		)
		(fp_line
			(start -0.12065 -0.305054)
			(end -0.12065 -0.2794)
			(stroke
				(width 0.1)
				(type default)
			)
			(layer "F.Fab")
		)
		(pad "1" smd circle
			(at -0.40005 0 270)
			(size 0 0)
			(layers "F.Cu" "F.Mask" "F.Paste")
			(net "SW_P12V_AUX_P0V9_RETIMER_CPU1_FLT")
		)
		(pad "2" smd circle
			(at 0.40005 0 270)
			(size 0 0)
			(layers "F.Cu" "F.Mask" "F.Paste")
			(net "GND")
		)
	)
	(footprint ""
		(layer "F.Cu")
		(at 360.76001 -418.329618 180)
		(property "Reference" "R4173"
			(at 0 0 180)
			(layer "F.SilkS")
			(hide yes)
			(effects
				(font
					(size 1.27 1.27)
				)
			)
		)
		(property "Value" ""
			(at 0 0 180)
			(layer "F.Fab")
			(effects
				(font
					(size 1.27 1.27)
				)
			)
		)
		(duplicate_pad_numbers_are_jumpers no)
		(fp_line
			(start 0.7874 0.4064)
			(end -0.7874 0.4064)
			(stroke
				(width 0.1524)
				(type default)
			)
			(layer "F.SilkS")
		)
		(fp_line
			(start 0.7874 -0.4064)
			(end 0.7874 0.4064)
			(stroke
				(width 0.1524)
				(type default)
			)
			(layer "F.SilkS")
		)
		(fp_line
			(start -0.7874 0.4064)
			(end -0.7874 -0.4064)
			(stroke
				(width 0.1524)
				(type default)
			)
			(layer "F.SilkS")
		)
		(fp_line
			(start -0.7874 -0.4064)
			(end 0.7874 -0.4064)
			(stroke
				(width 0.1524)
				(type default)
			)
			(layer "F.SilkS")
		)
		(fp_line
			(start 0.67945 0.3048)
			(end 0.120396 0.3048)
			(stroke
				(width 0.1)
				(type default)
			)
			(layer "F.Fab")
		)
		(fp_line
			(start 0.67945 -0.3048)
			(end 0.67945 0.3048)
			(stroke
				(width 0.1)
				(type default)
			)
			(layer "F.Fab")
		)
		(fp_line
			(start 0.12065 -0.2794)
			(end 0.12065 -0.3048)
			(stroke
				(width 0.1)
				(type default)
			)
			(layer "F.Fab")
		)
		(fp_line
			(start 0.12065 -0.3048)
			(end 0.67945 -0.3048)
			(stroke
				(width 0.1)
				(type default)
			)
			(layer "F.Fab")
		)
		(fp_line
			(start 0.120396 0.3048)
			(end 0.120396 0.2794)
			(stroke
				(width 0.1)
				(type default)
			)
			(layer "F.Fab")
		)
		(fp_line
			(start 0.120396 0.2794)
			(end -0.12065 0.2794)
			(stroke
				(width 0.1)
				(type default)
			)
			(layer "F.Fab")
		)
		(fp_line
			(start -0.12065 0.3048)
			(end -0.67945 0.3048)
			(stroke
				(width 0.1)
				(type default)
			)
			(layer "F.Fab")
		)
		(fp_line
			(start -0.12065 0.2794)
			(end -0.12065 0.3048)
			(stroke
				(width 0.1)
				(type default)
			)
			(layer "F.Fab")
		)
		(fp_line
			(start -0.12065 -0.2794)
			(end 0.12065 -0.2794)
			(stroke
				(width 0.1)
				(type default)
			)
			(layer "F.Fab")
		)
		(fp_line
			(start -0.12065 -0.305054)
			(end -0.12065 -0.2794)
			(stroke
				(width 0.1)
				(type default)
			)
			(layer "F.Fab")
		)
		(fp_line
			(start -0.67945 0.3048)
			(end -0.67945 -0.305054)
			(stroke
				(width 0.1)
				(type default)
			)
			(layer "F.Fab")
		)
		(fp_line
			(start -0.67945 -0.305054)
			(end -0.12065 -0.305054)
			(stroke
				(width 0.1)
				(type default)
			)
			(layer "F.Fab")
		)
		(pad "1" smd circle
			(at -0.40005 0 180)
			(size 0 0)
			(layers "F.Cu" "F.Mask" "F.Paste")
			(net "P3V3_AUX")
		)
		(pad "2" smd circle
			(at 0.40005 0 180)
			(size 0 0)
			(layers "F.Cu" "F.Mask" "F.Paste")
			(net "UART_BMC_BIC_R_BUF_RX")
		)
	)
	(footprint ""
		(layer "F.Cu")
		(at 109.949996 -401.329906 -90)
		(property "Reference" "U19"
			(at 4.252468 -3.081782 90)
			(unlocked yes)
			(layer "F.SilkS")
			(effects
				(font
					(size 0.7874 0.5842)
					(thickness 0.1524)
				)
				(justify left)
			)
		)
		(property "Value" ""
			(at 0 0 270)
			(layer "F.Fab")
			(effects
				(font
					(size 1.27 1.27)
				)
			)
		)
		(duplicate_pad_numbers_are_jumpers no)
		(fp_line
			(start -1.8288 2.500122)
			(end 1.8288 2.500122)
			(stroke
				(width 0.1524)
				(type default)
			)
			(layer "F.SilkS")
		)
		(fp_line
			(start 1.8288 2.500122)
			(end 1.8288 -2.500122)
			(stroke
				(width 0.1524)
				(type default)
			)
			(layer "F.SilkS")
		)
		(fp_line
			(start 0 -1.4224)
			(end -1.077722 -2.500122)
			(stroke
				(width 0.1524)
				(type default)
			)
			(layer "F.SilkS")
		)
		(fp_line
			(start -1.8288 -2.500122)
			(end -1.8288 2.500122)
			(stroke
				(width 0.1524)
				(type default)
			)
			(layer "F.SilkS")
		)
		(fp_line
			(start -1.077722 -2.500122)
			(end -1.8288 -2.500122)
			(stroke
				(width 0.1524)
				(type default)
			)
			(layer "F.SilkS")
		)
		(fp_line
			(start 1.077722 -2.500122)
			(end 0 -1.4224)
			(stroke
				(width 0.1524)
				(type default)
			)
			(layer "F.SilkS")
		)
		(fp_line
			(start 1.8288 -2.500122)
			(end 1.077722 -2.500122)
			(stroke
				(width 0.1524)
				(type default)
			)
			(layer "F.SilkS")
		)
		(fp_poly
			(pts
				(xy -4.5085 -2.413) (xy -4.5085 -1.397) (xy -3.4925 -1.905)
			)
			(stroke
				(width 0)
				(type default)
			)
			(fill yes)
			(layer "F.SilkS")
		)
		(fp_line
			(start -1.999996 2.500122)
			(end 1.999996 2.500122)
			(stroke
				(width 0.1)
				(type default)
			)
			(layer "F.Fab")
		)
		(fp_line
			(start 1.999996 2.500122)
			(end 1.999996 -2.500122)
			(stroke
				(width 0.1)
				(type default)
			)
			(layer "F.Fab")
		)
		(fp_line
			(start -1.999996 -2.500122)
			(end -1.999996 2.500122)
			(stroke
				(width 0.1)
				(type default)
			)
			(layer "F.Fab")
		)
		(fp_line
			(start 1.999996 -2.500122)
			(end -1.999996 -2.500122)
			(stroke
				(width 0.1)
				(type default)
			)
			(layer "F.Fab")
		)
		(fp_poly
			(pts
				(xy -4.5085 -2.413) (xy -4.5085 -1.397) (xy -3.4925 -1.905)
			)
			(stroke
				(width 0)
				(type default)
			)
			(fill yes)
			(layer "F.Fab")
		)
		(pad "1" smd rect
			(at -2.599944 -1.905 180)
			(size 0.889 1.27)
			(layers "F.Cu" "F.Mask" "F.Paste")
			(net "Net_10837")
		)
		(pad "2" smd rect
			(at -2.599944 -0.635 180)
			(size 0.889 1.27)
			(layers "F.Cu" "F.Mask" "F.Paste")
			(net "Net_10836")
		)
		(pad "3" smd rect
			(at -2.599944 0.635 180)
			(size 0.889 1.27)
			(layers "F.Cu" "F.Mask" "F.Paste")
			(net "U19_E2")
		)
		(pad "4" smd rect
			(at -2.599944 1.905 180)
			(size 0.889 1.27)
			(layers "F.Cu" "F.Mask" "F.Paste")
			(net "GND")
		)
		(pad "5" smd rect
			(at 2.599944 1.905 180)
			(size 0.889 1.27)
			(layers "F.Cu" "F.Mask" "F.Paste")
			(net "SMB_RT_CPU1_P1_ROM_SDA")
		)
		(pad "6" smd rect
			(at 2.599944 0.635 180)
			(size 0.889 1.27)
			(layers "F.Cu" "F.Mask" "F.Paste")
			(net "SMB_RT_CPU1_P1_ROM_SCL")
		)
		(pad "7" smd rect
			(at 2.599944 -0.635 180)
			(size 0.889 1.27)
			(layers "F.Cu" "F.Mask" "F.Paste")
			(net "GND")
		)
		(pad "8" smd rect
			(at 2.599944 -1.905 180)
			(size 0.889 1.27)
			(layers "F.Cu" "F.Mask" "F.Paste")
			(net "P1V8_CPU1_RT_1D")
		)
	)
	(footprint ""
		(layer "F.Cu")
		(at 20.416012 -358.30637 90)
		(property "Reference" "R8224"
			(at 0 0 90)
			(layer "F.SilkS")
			(hide yes)
			(effects
				(font
					(size 1.27 1.27)
				)
			)
		)
		(property "Value" ""
			(at 0 0 90)
			(layer "F.Fab")
			(effects
				(font
					(size 1.27 1.27)
				)
			)
		)
		(duplicate_pad_numbers_are_jumpers no)
		(fp_line
			(start 0.7874 -0.4064)
			(end 0.7874 0.4064)
			(stroke
				(width 0.1524)
				(type default)
			)
			(layer "F.SilkS")
		)
		(fp_line
			(start -0.7874 -0.4064)
			(end 0.7874 -0.4064)
			(stroke
				(width 0.1524)
				(type default)
			)
			(layer "F.SilkS")
		)
		(fp_line
			(start 0.7874 0.4064)
			(end -0.7874 0.4064)
			(stroke
				(width 0.1524)
				(type default)
			)
			(layer "F.SilkS")
		)
		(fp_line
			(start -0.7874 0.4064)
			(end -0.7874 -0.4064)
			(stroke
				(width 0.1524)
				(type default)
			)
			(layer "F.SilkS")
		)
		(fp_line
			(start -0.12065 -0.305054)
			(end -0.12065 -0.2794)
			(stroke
				(width 0.1)
				(type default)
			)
			(layer "F.Fab")
		)
		(fp_line
			(start -0.67945 -0.305054)
			(end -0.12065 -0.305054)
			(stroke
				(width 0.1)
				(type default)
			)
			(layer "F.Fab")
		)
		(fp_line
			(start 0.67945 -0.3048)
			(end 0.67945 0.3048)
			(stroke
				(width 0.1)
				(type default)
			)
			(layer "F.Fab")
		)
		(fp_line
			(start 0.12065 -0.3048)
			(end 0.67945 -0.3048)
			(stroke
				(width 0.1)
				(type default)
			)
			(layer "F.Fab")
		)
		(fp_line
			(start 0.12065 -0.2794)
			(end 0.12065 -0.3048)
			(stroke
				(width 0.1)
				(type default)
			)
			(layer "F.Fab")
		)
		(fp_line
			(start -0.12065 -0.2794)
			(end 0.12065 -0.2794)
			(stroke
				(width 0.1)
				(type default)
			)
			(layer "F.Fab")
		)
		(fp_line
			(start 0.120396 0.2794)
			(end -0.12065 0.2794)
			(stroke
				(width 0.1)
				(type default)
			)
			(layer "F.Fab")
		)
		(fp_line
			(start -0.12065 0.2794)
			(end -0.12065 0.3048)
			(stroke
				(width 0.1)
				(type default)
			)
			(layer "F.Fab")
		)
		(fp_line
			(start 0.67945 0.3048)
			(end 0.120396 0.3048)
			(stroke
				(width 0.1)
				(type default)
			)
			(layer "F.Fab")
		)
		(fp_line
			(start 0.120396 0.3048)
			(end 0.120396 0.2794)
			(stroke
				(width 0.1)
				(type default)
			)
			(layer "F.Fab")
		)
		(fp_line
			(start -0.12065 0.3048)
			(end -0.67945 0.3048)
			(stroke
				(width 0.1)
				(type default)
			)
			(layer "F.Fab")
		)
		(fp_line
			(start -0.67945 0.3048)
			(end -0.67945 -0.305054)
			(stroke
				(width 0.1)
				(type default)
			)
			(layer "F.Fab")
		)
		(pad "1" smd circle
			(at -0.40005 0 90)
			(size 0 0)
			(layers "F.Cu" "F.Mask" "F.Paste")
			(net "PVDDIO_P1_EN")
		)
		(pad "2" smd circle
			(at 0.40005 0 90)
			(size 0 0)
			(layers "F.Cu" "F.Mask" "F.Paste")
			(net "PVDDIO_P1_EN_R")
		)
	)
	(footprint ""
		(layer "F.Cu")
		(at 103.505 -419.989)
		(property "Reference" "R3493"
			(at 0 0 0)
			(layer "F.SilkS")
			(hide yes)
			(effects
				(font
					(size 1.27 1.27)
				)
			)
		)
		(property "Value" ""
			(at 0 0 0)
			(layer "F.Fab")
			(effects
				(font
					(size 1.27 1.27)
				)
			)
		)
		(duplicate_pad_numbers_are_jumpers no)
		(fp_line
			(start -0.7874 -0.4064)
			(end 0.7874 -0.4064)
			(stroke
				(width 0.1524)
				(type default)
			)
			(layer "F.SilkS")
		)
		(fp_line
			(start -0.7874 0.4064)
			(end -0.7874 -0.4064)
			(stroke
				(width 0.1524)
				(type default)
			)
			(layer "F.SilkS")
		)
		(fp_line
			(start 0.7874 -0.4064)
			(end 0.7874 0.4064)
			(stroke
				(width 0.1524)
				(type default)
			)
			(layer "F.SilkS")
		)
		(fp_line
			(start 0.7874 0.4064)
			(end -0.7874 0.4064)
			(stroke
				(width 0.1524)
				(type default)
			)
			(layer "F.SilkS")
		)
		(fp_line
			(start -0.67945 -0.305054)
			(end -0.12065 -0.305054)
			(stroke
				(width 0.1)
				(type default)
			)
			(layer "F.Fab")
		)
		(fp_line
			(start -0.67945 0.3048)
			(end -0.67945 -0.305054)
			(stroke
				(width 0.1)
				(type default)
			)
			(layer "F.Fab")
		)
		(fp_line
			(start -0.12065 -0.305054)
			(end -0.12065 -0.2794)
			(stroke
				(width 0.1)
				(type default)
			)
			(layer "F.Fab")
		)
		(fp_line
			(start -0.12065 -0.2794)
			(end 0.12065 -0.2794)
			(stroke
				(width 0.1)
				(type default)
			)
			(layer "F.Fab")
		)
		(fp_line
			(start -0.12065 0.2794)
			(end -0.12065 0.3048)
			(stroke
				(width 0.1)
				(type default)
			)
			(layer "F.Fab")
		)
		(fp_line
			(start -0.12065 0.3048)
			(end -0.67945 0.3048)
			(stroke
				(width 0.1)
				(type default)
			)
			(layer "F.Fab")
		)
		(fp_line
			(start 0.120396 0.2794)
			(end -0.12065 0.2794)
			(stroke
				(width 0.1)
				(type default)
			)
			(layer "F.Fab")
		)
		(fp_line
			(start 0.120396 0.3048)
			(end 0.120396 0.2794)
			(stroke
				(width 0.1)
				(type default)
			)
			(layer "F.Fab")
		)
		(fp_line
			(start 0.12065 -0.3048)
			(end 0.67945 -0.3048)
			(stroke
				(width 0.1)
				(type default)
			)
			(layer "F.Fab")
		)
		(fp_line
			(start 0.12065 -0.2794)
			(end 0.12065 -0.3048)
			(stroke
				(width 0.1)
				(type default)
			)
			(layer "F.Fab")
		)
		(fp_line
			(start 0.67945 -0.3048)
			(end 0.67945 0.3048)
			(stroke
				(width 0.1)
				(type default)
			)
			(layer "F.Fab")
		)
		(fp_line
			(start 0.67945 0.3048)
			(end 0.120396 0.3048)
			(stroke
				(width 0.1)
				(type default)
			)
			(layer "F.Fab")
		)
		(pad "1" smd circle
			(at -0.40005 0)
			(size 0 0)
			(layers "F.Cu" "F.Mask" "F.Paste")
			(net "GPU_FPGA_EROT_RST_BUF_R_N")
		)
		(pad "2" smd circle
			(at 0.40005 0)
			(size 0 0)
			(layers "F.Cu" "F.Mask" "F.Paste")
			(net "GND")
		)
	)
	(footprint ""
		(layer "F.Cu")
		(at 83.239102 -373.03583 -90)
		(property "Reference" "C730"
			(at 0 0 270)
			(layer "F.SilkS")
			(hide yes)
			(effects
				(font
					(size 1.27 1.27)
				)
			)
		)
		(property "Value" ""
			(at 0 0 270)
			(layer "F.Fab")
			(effects
				(font
					(size 1.27 1.27)
				)
			)
		)
		(duplicate_pad_numbers_are_jumpers no)
		(fp_line
			(start -0.299974 0.150114)
			(end -0.299974 -0.150114)
			(stroke
				(width 0.1)
				(type default)
			)
			(layer "F.Fab")
		)
		(fp_line
			(start 0.299974 0.150114)
			(end -0.299974 0.150114)
			(stroke
				(width 0.1)
				(type default)
			)
			(layer "F.Fab")
		)
		(fp_line
			(start -0.299974 -0.150114)
			(end 0.299974 -0.150114)
			(stroke
				(width 0.1)
				(type default)
			)
			(layer "F.Fab")
		)
		(fp_line
			(start 0.299974 -0.150114)
			(end 0.299974 0.150114)
			(stroke
				(width 0.1)
				(type default)
			)
			(layer "F.Fab")
		)
		(pad "1" smd rect
			(at -0.2667 0 270)
			(size 0.3048 0.381)
			(layers "F.Cu" "F.Mask" "F.Paste")
			(net "P5E_CPU1_P1_TX_C_DN<5>")
		)
		(pad "2" smd rect
			(at 0.2667 0 270)
			(size 0.3048 0.381)
			(layers "F.Cu" "F.Mask" "F.Paste")
			(net "P5E_CPU1_P1_TX_DN<5>")
		)
	)
	(footprint ""
		(layer "F.Cu")
		(at 281.94 -430.022 -90)
		(property "Reference" "L19"
			(at 0 0 270)
			(layer "F.SilkS")
			(hide yes)
			(effects
				(font
					(size 1.27 1.27)
				)
			)
		)
		(property "Value" ""
			(at 0 0 270)
			(layer "F.Fab")
			(effects
				(font
					(size 1.27 1.27)
				)
			)
		)
		(duplicate_pad_numbers_are_jumpers no)
		(fp_line
			(start 1.63576 0.8128)
			(end -1.63576 0.8128)
			(stroke
				(width 0.1524)
				(type default)
			)
			(layer "F.SilkS")
		)
		(fp_line
			(start -1.63576 -0.8128)
			(end -1.63576 0.8128)
			(stroke
				(width 0.1524)
				(type default)
			)
			(layer "F.SilkS")
		)
		(fp_line
			(start -1.63576 -0.8128)
			(end 1.63576 -0.8128)
			(stroke
				(width 0.1524)
				(type default)
			)
			(layer "F.SilkS")
		)
		(fp_line
			(start 1.63576 -0.8128)
			(end 1.63576 0.8128)
			(stroke
				(width 0.1524)
				(type default)
			)
			(layer "F.SilkS")
		)
		(fp_line
			(start -1.56083 0.7366)
			(end -1.524 0.7366)
			(stroke
				(width 0.1)
				(type default)
			)
			(layer "F.Fab")
		)
		(fp_line
			(start -1.524 0.7366)
			(end 1.524 0.7366)
			(stroke
				(width 0.1)
				(type default)
			)
			(layer "F.Fab")
		)
		(fp_line
			(start 1.524 0.7366)
			(end 1.560576 0.7366)
			(stroke
				(width 0.1)
				(type default)
			)
			(layer "F.Fab")
		)
		(fp_line
			(start 1.560576 0.7366)
			(end 1.560576 -0.738632)
			(stroke
				(width 0.1)
				(type default)
			)
			(layer "F.Fab")
		)
		(fp_line
			(start -1.56083 -0.738632)
			(end -1.56083 0.7366)
			(stroke
				(width 0.1)
				(type default)
			)
			(layer "F.Fab")
		)
		(fp_line
			(start 1.560576 -0.738632)
			(end -1.56083 -0.738632)
			(stroke
				(width 0.1)
				(type default)
			)
			(layer "F.Fab")
		)
		(pad "1" smd rect
			(at -0.94996 0 90)
			(size 1.1176 1.3716)
			(layers "F.Cu" "F.Mask" "F.Paste")
			(net "P3V3_AUX")
		)
		(pad "2" smd rect
			(at 0.94996 0 90)
			(size 1.1176 1.3716)
			(layers "F.Cu" "F.Mask" "F.Paste")
			(net "P3V3_9ZXL045_P0")
		)
	)
)
